(kicad_pcb
	(version 20241229)
	(generator "pcbnew")
	(generator_version "9.0")
	(general
		(thickness 1.6642)
		(legacy_teardrops no)
	)
	(paper "A3")
	(title_block
		(title "PolarFire SoM")
		(date "2025-07-22")
		(rev "1.1.4")
		(company "Antmicro Ltd")
		(comment 1 "www.antmicro.com")
		(comment 9 "footprints 421-425 of 470")
	)
	(layers
		(0 "F.Cu" mixed)
		(4 "In1.Cu" power)
		(6 "In2.Cu" signal)
		(8 "In3.Cu" power)
		(10 "In4.Cu" signal)
		(12 "In5.Cu" power)
		(14 "In6.Cu" power)
		(16 "In7.Cu" signal)
		(18 "In8.Cu" power)
		(20 "In9.Cu" signal)
		(22 "In10.Cu" power)
		(24 "In11.Cu" signal)
		(26 "In12.Cu" signal)
		(2 "B.Cu" mixed)
		(9 "F.Adhes" user "F.Adhesive")
		(11 "B.Adhes" user "B.Adhesive")
		(13 "F.Paste" user)
		(15 "B.Paste" user)
		(5 "F.SilkS" user "F.Silkscreen")
		(7 "B.SilkS" user "B.Silkscreen")
		(1 "F.Mask" user)
		(3 "B.Mask" user)
		(17 "Dwgs.User" user "User.Drawings")
		(19 "Cmts.User" user "User.Comments")
		(21 "Eco1.User" user "User.Eco1")
		(23 "Eco2.User" user "User.Eco2")
		(25 "Edge.Cuts" user)
		(27 "Margin" user)
		(31 "F.CrtYd" user "F.Courtyard")
		(29 "B.CrtYd" user "B.Courtyard")
		(35 "F.Fab" user)
		(33 "B.Fab" user)
	)
	(footprint "antmicro-footprints:R_0402_1005Metric"
		(layer "B.Cu")
		(at 198.975 121.7 90)
		(descr "Resistor SMD 0402")
		(tags "resistor SMD 0402")
		(property "Reference" "R55"
			(at -2.21 -0.305 270)
			(layer "B.SilkS")
			(effects
				(font
					(size 0.7 0.7)
					(thickness 0.15)
				)
				(justify left bottom mirror)
			)
		)
		(property "Value" "R_10k_0402"
			(at -1.011843 -1.772047 270)
			(layer "B.Fab")
			(hide yes)
			(effects
				(font
					(size 0.7 0.7)
					(thickness 0.15)
				)
				(justify left bottom mirror)
			)
		)
		(property "Datasheet" "https://www.bourns.com/docs/product-datasheets/cr.pdf"
			(at 0 0 90)
			(layer "F.Fab")
			(hide yes)
			(effects
				(font
					(size 1.27 1.27)
					(thickness 0.15)
				)
			)
		)
		(property "Description" "SMD Chip Resistor, 10 kohm, ± 1%, 62.5 mW, 0402 [1005 Metric], Thick Film, General Purpose"
			(at 0 0 90)
			(layer "F.Fab")
			(hide yes)
			(effects
				(font
					(size 1.27 1.27)
					(thickness 0.15)
				)
			)
		)
		(property "Author" "Antmicro"
			(at 320.675 -77.275 0)
			(layer "B.Fab")
			(hide yes)
			(effects
				(font
					(size 1 1)
					(thickness 0.15)
				)
				(justify mirror)
			)
		)
		(property "DNP" "DNP"
			(at 320.675 -77.275 0)
			(layer "B.Fab")
			(hide yes)
			(effects
				(font
					(size 1 1)
					(thickness 0.15)
				)
				(justify mirror)
			)
		)
		(property "License" "Apache-2.0"
			(at 320.675 -77.275 0)
			(layer "B.Fab")
			(hide yes)
			(effects
				(font
					(size 1 1)
					(thickness 0.15)
				)
				(justify mirror)
			)
		)
		(property "MPN" "CR0402-FX-1002GLF"
			(at 320.675 -77.275 0)
			(layer "B.Fab")
			(hide yes)
			(effects
				(font
					(size 1 1)
					(thickness 0.15)
				)
				(justify mirror)
			)
		)
		(property "Manufacturer" "Bourns"
			(at 320.675 -77.275 0)
			(layer "B.Fab")
			(hide yes)
			(effects
				(font
					(size 1 1)
					(thickness 0.15)
				)
				(justify mirror)
			)
		)
		(property "Public" ""
			(at 320.675 -77.275 0)
			(layer "B.Fab")
			(hide yes)
			(effects
				(font
					(size 1 1)
					(thickness 0.15)
				)
				(justify mirror)
			)
		)
		(property "Tolerance" "1%"
			(at 320.675 -77.275 0)
			(layer "B.Fab")
			(hide yes)
			(effects
				(font
					(size 1 1)
					(thickness 0.15)
				)
				(justify mirror)
			)
		)
		(property "Val" "10k"
			(at 320.675 -77.275 0)
			(layer "B.Fab")
			(hide yes)
			(effects
				(font
					(size 1 1)
					(thickness 0.15)
				)
				(justify mirror)
			)
		)
		(sheetname "/Memory/")
		(sheetfile "memory.kicad_sch")
		(attr smd dnp)
		(fp_rect
			(start -0.925 0.47)
			(end 0.925 -0.47)
			(stroke
				(width 0.05)
				(type default)
			)
			(fill no)
			(layer "B.CrtYd")
		)
		(fp_rect
			(start -0.5 0.25)
			(end 0.5 -0.25)
			(stroke
				(width 0.15)
				(type solid)
			)
			(fill no)
			(layer "B.Fab")
		)
		(fp_text user "Author: Antmicro"
			(at -0.95 -4.169 270)
			(layer "B.Fab")
			(effects
				(font
					(size 0.7 0.7)
					(thickness 0.15)
				)
				(justify left bottom mirror)
			)
		)
		(fp_text user "${REFERENCE}"
			(at -0.95 -3.168 270)
			(layer "B.Fab")
			(effects
				(font
					(size 0.7 0.7)
					(thickness 0.15)
				)
				(justify left bottom mirror)
			)
		)
		(fp_text user "License: Apache-2.0"
			(at -0.95 -5.169 270)
			(layer "B.Fab")
			(effects
				(font
					(size 0.7 0.7)
					(thickness 0.15)
				)
				(justify left bottom mirror)
			)
		)
		(pad "1" smd roundrect
			(at -0.48 0 90)
			(size 0.59 0.64)
			(layers "B.Cu" "B.Mask" "B.Paste")
			(roundrect_rratio 0.25)
			(net 417 "GND")
			(pintype "passive")
		)
		(pad "2" smd roundrect
			(at 0.48 0 90)
			(size 0.59 0.64)
			(layers "B.Cu" "B.Mask" "B.Paste")
			(roundrect_rratio 0.25)
			(net 44 "SD_PWR_ON")
			(pintype "passive")
		)
	)
	(footprint "antmicro-footprints:C_0402_1005Metric"
		(layer "B.Cu")
		(at 189.28 144.65 180)
		(descr "Capacitor SMD 0402")
		(tags "capacitor SMD 0402")
		(property "Reference" "C43"
			(at -2.45 -4.08 0)
			(layer "B.SilkS")
			(effects
				(font
					(size 0.7 0.7)
					(thickness 0.15)
				)
				(justify left bottom mirror)
			)
		)
		(property "Value" "C_100n_0402"
			(at -1.022927 -2.155213 0)
			(layer "B.Fab")
			(hide yes)
			(effects
				(font
					(size 0.7 0.7)
					(thickness 0.15)
				)
				(justify left bottom mirror)
			)
		)
		(property "Datasheet" "https://www.murata.com/products/productdetail?partno=GRM155R61H104KE14%23"
			(at 0 0 180)
			(layer "F.Fab")
			(hide yes)
			(effects
				(font
					(size 1.27 1.27)
					(thickness 0.15)
				)
			)
		)
		(property "Description" "SMD Multilayer Ceramic Capacitor, 0.1 µF, 50 V, 0402 [1005 Metric], ± 10%, X5R, GRM Series"
			(at 0 0 180)
			(layer "F.Fab")
			(hide yes)
			(effects
				(font
					(size 1.27 1.27)
					(thickness 0.15)
				)
			)
		)
		(property "Author" "Antmicro"
			(at 378.56 289.3 0)
			(layer "B.Fab")
			(hide yes)
			(effects
				(font
					(size 1 1)
					(thickness 0.15)
				)
				(justify mirror)
			)
		)
		(property "Dielectric" "X5R"
			(at 378.56 289.3 0)
			(layer "B.Fab")
			(hide yes)
			(effects
				(font
					(size 1 1)
					(thickness 0.15)
				)
				(justify mirror)
			)
		)
		(property "License" "Apache-2.0"
			(at 378.56 289.3 0)
			(layer "B.Fab")
			(hide yes)
			(effects
				(font
					(size 1 1)
					(thickness 0.15)
				)
				(justify mirror)
			)
		)
		(property "MPN" "GRM155R61H104KE14D"
			(at 378.56 289.3 0)
			(layer "B.Fab")
			(hide yes)
			(effects
				(font
					(size 1 1)
					(thickness 0.15)
				)
				(justify mirror)
			)
		)
		(property "Manufacturer" "Murata"
			(at 378.56 289.3 0)
			(layer "B.Fab")
			(hide yes)
			(effects
				(font
					(size 1 1)
					(thickness 0.15)
				)
				(justify mirror)
			)
		)
		(property "Public" ""
			(at 378.56 289.3 0)
			(layer "B.Fab")
			(hide yes)
			(effects
				(font
					(size 1 1)
					(thickness 0.15)
				)
				(justify mirror)
			)
		)
		(property "Val" "100n"
			(at 378.56 289.3 0)
			(layer "B.Fab")
			(hide yes)
			(effects
				(font
					(size 1 1)
					(thickness 0.15)
				)
				(justify mirror)
			)
		)
		(property "Voltage" "50V"
			(at 378.56 289.3 0)
			(layer "B.Fab")
			(hide yes)
			(effects
				(font
					(size 1 1)
					(thickness 0.15)
				)
				(justify mirror)
			)
		)
		(sheetname "/FPGA Supply/")
		(sheetfile "fpga-supply.kicad_sch")
		(attr smd)
		(fp_rect
			(start -0.925 0.47)
			(end 0.925 -0.47)
			(stroke
				(width 0.05)
				(type default)
			)
			(fill no)
			(layer "B.CrtYd")
		)
		(fp_line
			(start 0.504 0.25)
			(end 0.504 -0.248)
			(stroke
				(width 0.15)
				(type solid)
			)
			(layer "B.Fab")
		)
		(fp_line
			(start 0.504 -0.248)
			(end -0.494 -0.248)
			(stroke
				(width 0.15)
				(type solid)
			)
			(layer "B.Fab")
		)
		(fp_line
			(start -0.494 0.25)
			(end 0.504 0.25)
			(stroke
				(width 0.15)
				(type solid)
			)
			(layer "B.Fab")
		)
		(fp_line
			(start -0.494 -0.248)
			(end -0.494 0.25)
			(stroke
				(width 0.15)
				(type solid)
			)
			(layer "B.Fab")
		)
		(fp_text user "${REFERENCE}"
			(at -0.939 -4.599 0)
			(layer "B.Fab")
			(effects
				(font
					(size 0.7 0.7)
					(thickness 0.15)
				)
				(justify left bottom mirror)
			)
		)
		(fp_text user "License: Apache-2.0"
			(at -0.939 -5.799 0)
			(layer "B.Fab")
			(effects
				(font
					(size 0.7 0.7)
					(thickness 0.15)
				)
				(justify left bottom mirror)
			)
		)
		(fp_text user "Author: Antmicro"
			(at -0.939 -3.399 0)
			(layer "B.Fab")
			(effects
				(font
					(size 0.7 0.7)
					(thickness 0.15)
				)
				(justify left bottom mirror)
			)
		)
		(pad "1" smd roundrect
			(at -0.48 0 180)
			(size 0.59 0.64)
			(layers "B.Cu" "B.Mask" "B.Paste")
			(roundrect_rratio 0.25)
			(net 417 "GND")
			(pintype "passive")
		)
		(pad "2" smd roundrect
			(at 0.48 0 180)
			(size 0.59 0.64)
			(layers "B.Cu" "B.Mask" "B.Paste")
			(roundrect_rratio 0.25)
			(net 47 "+1V05")
			(pintype "passive")
		)
	)
	(footprint "antmicro-footprints:TP_SMD_0.75mm"
		(layer "B.Cu")
		(at 187.15 139.125 180)
		(property "Reference" "TP39"
			(at 0 0.6 0)
			(layer "B.SilkS")
			(hide yes)
			(effects
				(font
					(size 0.7 0.7)
					(thickness 0.15)
				)
				(justify left bottom mirror)
			)
		)
		(property "Value" "TP_0.75mm_SMD"
			(at 0 -1.2 0)
			(layer "B.Fab")
			(hide yes)
			(effects
				(font
					(size 0.7 0.7)
					(thickness 0.15)
				)
				(justify left bottom mirror)
			)
		)
		(property "Description" "SMT test point"
			(at 0 0 0)
			(layer "B.Fab")
			(hide yes)
			(effects
				(font
					(size 1.27 1.27)
					(thickness 0.15)
				)
				(justify mirror)
			)
		)
		(property "MPN" ""
			(at 0 0 0)
			(unlocked yes)
			(layer "B.Fab")
			(hide yes)
			(effects
				(font
					(size 1 1)
					(thickness 0.15)
				)
				(justify mirror)
			)
		)
		(property "Manufacturer" ""
			(at 0 0 0)
			(unlocked yes)
			(layer "B.Fab")
			(hide yes)
			(effects
				(font
					(size 1 1)
					(thickness 0.15)
				)
				(justify mirror)
			)
		)
		(property "Author" "Antmicro"
			(at 0 0 0)
			(unlocked yes)
			(layer "B.Fab")
			(hide yes)
			(effects
				(font
					(size 1 1)
					(thickness 0.15)
				)
				(justify mirror)
			)
		)
		(property "License" "Apache-2.0"
			(at 0 0 0)
			(unlocked yes)
			(layer "B.Fab")
			(hide yes)
			(effects
				(font
					(size 1 1)
					(thickness 0.15)
				)
				(justify mirror)
			)
		)
		(property "Public" "False"
			(at 0 0 0)
			(unlocked yes)
			(layer "B.Fab")
			(hide yes)
			(effects
				(font
					(size 1 1)
					(thickness 0.15)
				)
				(justify mirror)
			)
		)
		(sheetname "/Supply/")
		(sheetfile "supply.kicad_sch")
		(attr exclude_from_pos_files exclude_from_bom)
		(fp_circle
			(center 0 0)
			(end 0.475 0)
			(stroke
				(width 0.05)
				(type default)
			)
			(fill no)
			(layer "B.CrtYd")
		)
		(fp_text user "License: Apache-2.0"
			(at -0.4 -5.101 0)
			(layer "B.Fab")
			(effects
				(font
					(size 0.7 0.7)
					(thickness 0.15)
				)
				(justify left bottom mirror)
			)
		)
		(fp_text user "${REFERENCE}"
			(at -0.4 -2.7 0)
			(layer "B.Fab")
			(effects
				(font
					(size 0.7 0.7)
					(thickness 0.15)
				)
				(justify left bottom mirror)
			)
		)
		(fp_text user "Author: Antmicro"
			(at -0.4 -3.901 0)
			(layer "B.Fab")
			(effects
				(font
					(size 0.7 0.7)
					(thickness 0.15)
				)
				(justify left bottom mirror)
			)
		)
		(pad "1" smd circle
			(at 0 0 180)
			(size 0.75 0.75)
			(layers "B.Cu" "B.Mask")
			(net 90 "+5V")
			(pinfunction "1")
			(pintype "passive")
		)
	)
	(footprint "antmicro-footprints:C_0402_1005Metric"
		(layer "B.Cu")
		(at 199.91 138.63 90)
		(descr "Capacitor SMD 0402")
		(tags "capacitor SMD 0402")
		(property "Reference" "C25"
			(at 4.88 -9.685 90)
			(layer "B.SilkS")
			(effects
				(font
					(size 0.7 0.7)
					(thickness 0.15)
				)
				(justify right bottom mirror)
			)
		)
		(property "Value" "C_4n7_0402"
			(at -1.022927 -2.155213 90)
			(layer "B.Fab")
			(hide yes)
			(effects
				(font
					(size 0.7 0.7)
					(thickness 0.15)
				)
				(justify right bottom mirror)
			)
		)
		(property "Datasheet" "https://product.tdk.com/en/search/capacitor/ceramic/mlcc/info?part_no=CGA2B3X7S2A472K050BB"
			(at 0 0 90)
			(layer "F.Fab")
			(hide yes)
			(effects
				(font
					(size 1.27 1.27)
					(thickness 0.15)
				)
			)
		)
		(property "Description" "SMD Multilayer Ceramic Capacitor, 4700 pF, 100 V, 0402 [1005 Metric], ± 10%, X7S, CGA"
			(at 0 0 90)
			(layer "F.Fab")
			(hide yes)
			(effects
				(font
					(size 1.27 1.27)
					(thickness 0.15)
				)
			)
		)
		(property "Author" "Antmicro"
			(at 338.54 -61.28 0)
			(layer "B.Fab")
			(hide yes)
			(effects
				(font
					(size 1 1)
					(thickness 0.15)
				)
				(justify mirror)
			)
		)
		(property "Dielectric" "X7R"
			(at 338.54 -61.28 0)
			(layer "B.Fab")
			(hide yes)
			(effects
				(font
					(size 1 1)
					(thickness 0.15)
				)
				(justify mirror)
			)
		)
		(property "License" "Apache-2.0"
			(at 338.54 -61.28 0)
			(layer "B.Fab")
			(hide yes)
			(effects
				(font
					(size 1 1)
					(thickness 0.15)
				)
				(justify mirror)
			)
		)
		(property "MPN" "CGA2B3X7S2A472K050BB"
			(at 338.54 -61.28 0)
			(layer "B.Fab")
			(hide yes)
			(effects
				(font
					(size 1 1)
					(thickness 0.15)
				)
				(justify mirror)
			)
		)
		(property "Manufacturer" "TDK"
			(at 338.54 -61.28 0)
			(layer "B.Fab")
			(hide yes)
			(effects
				(font
					(size 1 1)
					(thickness 0.15)
				)
				(justify mirror)
			)
		)
		(property "Public" ""
			(at 338.54 -61.28 0)
			(layer "B.Fab")
			(hide yes)
			(effects
				(font
					(size 1 1)
					(thickness 0.15)
				)
				(justify mirror)
			)
		)
		(property "Val" "4n7"
			(at 338.54 -61.28 0)
			(layer "B.Fab")
			(hide yes)
			(effects
				(font
					(size 1 1)
					(thickness 0.15)
				)
				(justify mirror)
			)
		)
		(property "Voltage" "25V"
			(at 338.54 -61.28 0)
			(layer "B.Fab")
			(hide yes)
			(effects
				(font
					(size 1 1)
					(thickness 0.15)
				)
				(justify mirror)
			)
		)
		(sheetname "/FPGA Supply/")
		(sheetfile "fpga-supply.kicad_sch")
		(attr smd)
		(fp_rect
			(start -0.925 0.47)
			(end 0.925 -0.47)
			(stroke
				(width 0.05)
				(type default)
			)
			(fill no)
			(layer "B.CrtYd")
		)
		(fp_line
			(start 0.504 -0.248)
			(end -0.494 -0.248)
			(stroke
				(width 0.15)
				(type solid)
			)
			(layer "B.Fab")
		)
		(fp_line
			(start -0.494 -0.248)
			(end -0.494 0.25)
			(stroke
				(width 0.15)
				(type solid)
			)
			(layer "B.Fab")
		)
		(fp_line
			(start 0.504 0.25)
			(end 0.504 -0.248)
			(stroke
				(width 0.15)
				(type solid)
			)
			(layer "B.Fab")
		)
		(fp_line
			(start -0.494 0.25)
			(end 0.504 0.25)
			(stroke
				(width 0.15)
				(type solid)
			)
			(layer "B.Fab")
		)
		(fp_text user "${REFERENCE}"
			(at -0.939 -4.599 270)
			(layer "B.Fab")
			(effects
				(font
					(size 0.7 0.7)
					(thickness 0.15)
				)
				(justify left bottom mirror)
			)
		)
		(fp_text user "License: Apache-2.0"
			(at -0.939 -5.799 270)
			(layer "B.Fab")
			(effects
				(font
					(size 0.7 0.7)
					(thickness 0.15)
				)
				(justify left bottom mirror)
			)
		)
		(fp_text user "Author: Antmicro"
			(at -0.939 -3.399 270)
			(layer "B.Fab")
			(effects
				(font
					(size 0.7 0.7)
					(thickness 0.15)
				)
				(justify left bottom mirror)
			)
		)
		(pad "1" smd roundrect
			(at -0.48 0 90)
			(size 0.59 0.64)
			(layers "B.Cu" "B.Mask" "B.Paste")
			(roundrect_rratio 0.25)
			(net 417 "GND")
			(pintype "passive")
		)
		(pad "2" smd roundrect
			(at 0.48 0 90)
			(size 0.59 0.64)
			(layers "B.Cu" "B.Mask" "B.Paste")
			(roundrect_rratio 0.25)
			(net 418 "+2V5")
			(pintype "passive")
		)
	)
	(footprint "antmicro-footprints:C_0402_1005Metric"
		(layer "B.Cu")
		(at 177.7 125.1 -90)
		(descr "Capacitor SMD 0402")
		(tags "capacitor SMD 0402")
		(property "Reference" "C142"
			(at -1.3 -1.36 90)
			(layer "B.SilkS")
			(effects
				(font
					(size 0.7 0.7)
					(thickness 0.15)
				)
				(justify left bottom mirror)
			)
		)
		(property "Value" "C_1u_0402"
			(at -1.022927 -2.155213 90)
			(layer "B.Fab")
			(hide yes)
			(effects
				(font
					(size 0.7 0.7)
					(thickness 0.15)
				)
				(justify left bottom mirror)
			)
		)
		(property "Datasheet" "https://product.tdk.com/en/search/capacitor/ceramic/mlcc/info?part_no=C1005X6S1A105K050BC"
			(at 0 0 270)
			(layer "F.Fab")
			(hide yes)
			(effects
				(font
					(size 1.27 1.27)
					(thickness 0.15)
				)
			)
		)
		(property "Description" "SMD Multilayer Ceramic Capacitor, 1 µF, 10 V, 0402 [1005 Metric], ± 10%, X6S, C"
			(at 0 0 270)
			(layer "F.Fab")
			(hide yes)
			(effects
				(font
					(size 1.27 1.27)
					(thickness 0.15)
				)
			)
		)
		(property "Author" "Antmicro"
			(at 52.6 302.8 0)
			(layer "B.Fab")
			(hide yes)
			(effects
				(font
					(size 1 1)
					(thickness 0.15)
				)
				(justify mirror)
			)
		)
		(property "Dielectric" "X5R"
			(at 52.6 302.8 0)
			(layer "B.Fab")
			(hide yes)
			(effects
				(font
					(size 1 1)
					(thickness 0.15)
				)
				(justify mirror)
			)
		)
		(property "License" "Apache-2.0"
			(at 52.6 302.8 0)
			(layer "B.Fab")
			(hide yes)
			(effects
				(font
					(size 1 1)
					(thickness 0.15)
				)
				(justify mirror)
			)
		)
		(property "MPN" "C1005X6S1A105K050BC"
			(at 52.6 302.8 0)
			(layer "B.Fab")
			(hide yes)
			(effects
				(font
					(size 1 1)
					(thickness 0.15)
				)
				(justify mirror)
			)
		)
		(property "Manufacturer" "TDK"
			(at 52.6 302.8 0)
			(layer "B.Fab")
			(hide yes)
			(effects
				(font
					(size 1 1)
					(thickness 0.15)
				)
				(justify mirror)
			)
		)
		(property "Public" ""
			(at 52.6 302.8 0)
			(layer "B.Fab")
			(hide yes)
			(effects
				(font
					(size 1 1)
					(thickness 0.15)
				)
				(justify mirror)
			)
		)
		(property "Val" "1u"
			(at 52.6 302.8 0)
			(layer "B.Fab")
			(hide yes)
			(effects
				(font
					(size 1 1)
					(thickness 0.15)
				)
				(justify mirror)
			)
		)
		(property "Voltage" "16V"
			(at 52.6 302.8 0)
			(layer "B.Fab")
			(hide yes)
			(effects
				(font
					(size 1 1)
					(thickness 0.15)
				)
				(justify mirror)
			)
		)
		(sheetname "/LPDDR4/")
		(sheetfile "lpddr.kicad_sch")
		(attr smd)
		(fp_rect
			(start -0.925 0.47)
			(end 0.925 -0.47)
			(stroke
				(width 0.05)
				(type default)
			)
			(fill no)
			(layer "B.CrtYd")
		)
		(fp_line
			(start -0.494 0.25)
			(end 0.504 0.25)
			(stroke
				(width 0.15)
				(type solid)
			)
			(layer "B.Fab")
		)
		(fp_line
			(start 0.504 0.25)
			(end 0.504 -0.248)
			(stroke
				(width 0.15)
				(type solid)
			)
			(layer "B.Fab")
		)
		(fp_line
			(start -0.494 -0.248)
			(end -0.494 0.25)
			(stroke
				(width 0.15)
				(type solid)
			)
			(layer "B.Fab")
		)
		(fp_line
			(start 0.504 -0.248)
			(end -0.494 -0.248)
			(stroke
				(width 0.15)
				(type solid)
			)
			(layer "B.Fab")
		)
		(fp_text user "License: Apache-2.0"
			(at -0.939 -5.799 90)
			(layer "B.Fab")
			(effects
				(font
					(size 0.7 0.7)
					(thickness 0.15)
				)
				(justify left bottom mirror)
			)
		)
		(fp_text user "${REFERENCE}"
			(at -0.939 -4.599 90)
			(layer "B.Fab")
			(effects
				(font
					(size 0.7 0.7)
					(thickness 0.15)
				)
				(justify left bottom mirror)
			)
		)
		(fp_text user "Author: Antmicro"
			(at -0.939 -3.399 90)
			(layer "B.Fab")
			(effects
				(font
					(size 0.7 0.7)
					(thickness 0.15)
				)
				(justify left bottom mirror)
			)
		)
		(pad "1" smd roundrect
			(at -0.48 0 270)
			(size 0.59 0.64)
			(layers "B.Cu" "B.Mask" "B.Paste")
			(roundrect_rratio 0.25)
			(net 417 "GND")
			(pintype "passive")
		)
		(pad "2" smd roundrect
			(at 0.48 0 270)
			(size 0.59 0.64)
			(layers "B.Cu" "B.Mask" "B.Paste")
			(roundrect_rratio 0.25)
			(net 2 "+1V1")
			(pintype "passive")
		)
	)
)
